(kicad_pcb
	(version 20260206)
	(generator "pcbnew")
	(generator_version "10.0")
	(general
		(thickness 1.6)
		(legacy_teardrops no)
	)
	(paper "A4")
	(title_block
		(title "03242023_DA0F0TMBIJ0_F0T_Motherboard_J_brd_V01_OCP.brd")
		(comment 1 "Grand Teton / footprints 2319-2325 of 6105")
	)
	(layers
		(0 "F.Cu" signal "TOP")
		(4 "In1.Cu" signal "GND")
		(6 "In2.Cu" signal "IN1")
		(8 "In3.Cu" signal "GND1")
		(10 "In4.Cu" signal "IN2")
		(12 "In5.Cu" signal "GND2")
		(14 "In6.Cu" signal "IN3")
		(16 "In7.Cu" signal "GND3")
		(18 "In8.Cu" signal "VCC")
		(20 "In9.Cu" signal "VCC1")
		(22 "In10.Cu" signal "GND4")
		(24 "In11.Cu" signal "IN4")
		(26 "In12.Cu" signal "GND5")
		(28 "In13.Cu" signal "IN5")
		(30 "In14.Cu" signal "GND6")
		(32 "In15.Cu" signal "IN6")
		(34 "In16.Cu" signal "GND7")
		(2 "B.Cu" signal "BOTTOM")
		(9 "F.Adhes" user "F.Adhesive")
		(11 "B.Adhes" user "B.Adhesive")
		(13 "F.Paste" user "Package Geometry/Pastemask Top")
		(15 "B.Paste" user "Package Geometry/Pastemask Bottom")
		(5 "F.SilkS" user "Ref Des/Silkscreen Top")
		(7 "B.SilkS" user "Ref Des/Silkscreen Bottom")
		(1 "F.Mask" user "Board Geometry/Soldermask Top")
		(3 "B.Mask" user "Board Geometry/Soldermask Bottom")
		(17 "Dwgs.User" user "User.Drawings")
		(19 "Cmts.User" user "User.Comments")
		(21 "Eco1.User" user "User.Eco1")
		(23 "Eco2.User" user "User.Eco2")
		(25 "Edge.Cuts" user "Board Geometry/Outline")
		(27 "Margin" user)
		(31 "F.CrtYd" user "Package Geometry/Place Bound Top")
		(29 "B.CrtYd" user "Package Geometry/Place Bound Bottom")
		(35 "F.Fab" user "Ref Des/Assembly Top")
		(33 "B.Fab" user "Ref Des/Assembly Bottom")
	)
	(footprint ""
		(layer "F.Cu")
		(at 329.524868 -73.509378 90)
		(property "Reference" "R4304"
			(at 0 0 90)
			(layer "F.SilkS")
			(hide yes)
			(effects
				(font
					(size 1.27 1.27)
				)
			)
		)
		(property "Value" ""
			(at 0 0 90)
			(layer "F.Fab")
			(effects
				(font
					(size 1.27 1.27)
				)
			)
		)
		(duplicate_pad_numbers_are_jumpers no)
		(fp_line
			(start 0.7874 -0.4064)
			(end 0.7874 0.4064)
			(stroke
				(width 0.1524)
				(type default)
			)
			(layer "F.SilkS")
		)
		(fp_line
			(start -0.7874 -0.4064)
			(end 0.7874 -0.4064)
			(stroke
				(width 0.1524)
				(type default)
			)
			(layer "F.SilkS")
		)
		(fp_line
			(start 0.7874 0.4064)
			(end -0.7874 0.4064)
			(stroke
				(width 0.1524)
				(type default)
			)
			(layer "F.SilkS")
		)
		(fp_line
			(start -0.7874 0.4064)
			(end -0.7874 -0.4064)
			(stroke
				(width 0.1524)
				(type default)
			)
			(layer "F.SilkS")
		)
		(fp_line
			(start -0.12065 -0.305054)
			(end -0.12065 -0.2794)
			(stroke
				(width 0.1)
				(type default)
			)
			(layer "F.Fab")
		)
		(fp_line
			(start -0.67945 -0.305054)
			(end -0.12065 -0.305054)
			(stroke
				(width 0.1)
				(type default)
			)
			(layer "F.Fab")
		)
		(fp_line
			(start 0.67945 -0.3048)
			(end 0.67945 0.3048)
			(stroke
				(width 0.1)
				(type default)
			)
			(layer "F.Fab")
		)
		(fp_line
			(start 0.12065 -0.3048)
			(end 0.67945 -0.3048)
			(stroke
				(width 0.1)
				(type default)
			)
			(layer "F.Fab")
		)
		(fp_line
			(start 0.12065 -0.2794)
			(end 0.12065 -0.3048)
			(stroke
				(width 0.1)
				(type default)
			)
			(layer "F.Fab")
		)
		(fp_line
			(start -0.12065 -0.2794)
			(end 0.12065 -0.2794)
			(stroke
				(width 0.1)
				(type default)
			)
			(layer "F.Fab")
		)
		(fp_line
			(start 0.120396 0.2794)
			(end -0.12065 0.2794)
			(stroke
				(width 0.1)
				(type default)
			)
			(layer "F.Fab")
		)
		(fp_line
			(start -0.12065 0.2794)
			(end -0.12065 0.3048)
			(stroke
				(width 0.1)
				(type default)
			)
			(layer "F.Fab")
		)
		(fp_line
			(start 0.67945 0.3048)
			(end 0.120396 0.3048)
			(stroke
				(width 0.1)
				(type default)
			)
			(layer "F.Fab")
		)
		(fp_line
			(start 0.120396 0.3048)
			(end 0.120396 0.2794)
			(stroke
				(width 0.1)
				(type default)
			)
			(layer "F.Fab")
		)
		(fp_line
			(start -0.12065 0.3048)
			(end -0.67945 0.3048)
			(stroke
				(width 0.1)
				(type default)
			)
			(layer "F.Fab")
		)
		(fp_line
			(start -0.67945 0.3048)
			(end -0.67945 -0.305054)
			(stroke
				(width 0.1)
				(type default)
			)
			(layer "F.Fab")
		)
		(pad "1" smd circle
			(at -0.40005 0 90)
			(size 0 0)
			(layers "F.Cu" "F.Mask" "F.Paste")
			(net "CLK_100M_E1S_0_R_DN")
		)
		(pad "2" smd circle
			(at 0.40005 0 90)
			(size 0 0)
			(layers "F.Cu" "F.Mask" "F.Paste")
			(net "CLK_100M_E1S_0_DN")
		)
	)
	(footprint ""
		(layer "F.Cu")
		(at 463.90687 -75.960224 90)
		(property "Reference" "PC566"
			(at 0 0 90)
			(layer "F.SilkS")
			(hide yes)
			(effects
				(font
					(size 1.27 1.27)
				)
			)
		)
		(property "Value" ""
			(at 0 0 90)
			(layer "F.Fab")
			(effects
				(font
					(size 1.27 1.27)
				)
			)
		)
		(duplicate_pad_numbers_are_jumpers no)
		(fp_line
			(start -3.400044 1.249934)
			(end 3.400044 1.249934)
			(stroke
				(width 0.1524)
				(type default)
			)
			(layer "F.SilkS")
		)
		(fp_circle
			(center 0 1.249934)
			(end 0 4.649978)
			(stroke
				(width 0.1524)
				(type default)
			)
			(fill no)
			(layer "F.SilkS")
		)
		(fp_poly
			(pts
				(arc
					(start -3.400044 1.249934)
					(mid 0 4.649978)
					(end 3.400044 1.249934)
				)
			)
			(stroke
				(width 0)
				(type default)
			)
			(fill yes)
			(layer "F.SilkS")
		)
		(fp_circle
			(center 0 1.249934)
			(end 0 4.649978)
			(stroke
				(width 0.1)
				(type default)
			)
			(fill no)
			(layer "F.Fab")
		)
		(pad "1" thru_hole rect
			(at 0 0 90)
			(size 1.524 1.524)
			(drill 1.016)
			(layers "*.Cu" "*.Mask")
			(remove_unused_layers no)
			(net "SW_P3V3_AUX_FLT")
			(clearance 0)
			(padstack
				(mode front_inner_back)
				(layer "Inner"
					(shape circle)
					(size 1.524 1.524)
					(clearance 0)
				)
				(layer "B.Cu"
					(shape rect)
					(size 1.524 1.524)
					(clearance 0)
				)
			)
		)
		(pad "2" thru_hole circle
			(at 0 2.500122 90)
			(size 1.524 1.524)
			(drill 1.016)
			(layers "*.Cu" "*.Mask")
			(remove_unused_layers no)
			(net "GND")
			(clearance 0)
		)
	)
	(footprint ""
		(layer "F.Cu")
		(at 155.634944 -44.64685 90)
		(property "Reference" "R4454"
			(at 0 0 90)
			(layer "F.SilkS")
			(hide yes)
			(effects
				(font
					(size 1.27 1.27)
				)
			)
		)
		(property "Value" ""
			(at 0 0 90)
			(layer "F.Fab")
			(effects
				(font
					(size 1.27 1.27)
				)
			)
		)
		(duplicate_pad_numbers_are_jumpers no)
		(fp_line
			(start 0.7874 -0.4064)
			(end 0.7874 0.4064)
			(stroke
				(width 0.1524)
				(type default)
			)
			(layer "F.SilkS")
		)
		(fp_line
			(start -0.7874 -0.4064)
			(end 0.7874 -0.4064)
			(stroke
				(width 0.1524)
				(type default)
			)
			(layer "F.SilkS")
		)
		(fp_line
			(start -0.12065 -0.305054)
			(end -0.12065 -0.2794)
			(stroke
				(width 0.1)
				(type default)
			)
			(layer "F.Fab")
		)
		(fp_line
			(start -0.67945 -0.305054)
			(end -0.12065 -0.305054)
			(stroke
				(width 0.1)
				(type default)
			)
			(layer "F.Fab")
		)
		(fp_line
			(start 0.67945 -0.3048)
			(end 0.67945 0.3048)
			(stroke
				(width 0.1)
				(type default)
			)
			(layer "F.Fab")
		)
		(fp_line
			(start 0.12065 -0.3048)
			(end 0.67945 -0.3048)
			(stroke
				(width 0.1)
				(type default)
			)
			(layer "F.Fab")
		)
		(fp_line
			(start 0.12065 -0.2794)
			(end 0.12065 -0.3048)
			(stroke
				(width 0.1)
				(type default)
			)
			(layer "F.Fab")
		)
		(fp_line
			(start -0.12065 -0.2794)
			(end 0.12065 -0.2794)
			(stroke
				(width 0.1)
				(type default)
			)
			(layer "F.Fab")
		)
		(fp_line
			(start 0.120396 0.2794)
			(end -0.12065 0.2794)
			(stroke
				(width 0.1)
				(type default)
			)
			(layer "F.Fab")
		)
		(fp_line
			(start -0.12065 0.2794)
			(end -0.12065 0.3048)
			(stroke
				(width 0.1)
				(type default)
			)
			(layer "F.Fab")
		)
		(fp_line
			(start 0.67945 0.3048)
			(end 0.120396 0.3048)
			(stroke
				(width 0.1)
				(type default)
			)
			(layer "F.Fab")
		)
		(fp_line
			(start 0.120396 0.3048)
			(end 0.120396 0.2794)
			(stroke
				(width 0.1)
				(type default)
			)
			(layer "F.Fab")
		)
		(fp_line
			(start -0.12065 0.3048)
			(end -0.67945 0.3048)
			(stroke
				(width 0.1)
				(type default)
			)
			(layer "F.Fab")
		)
		(fp_line
			(start -0.67945 0.3048)
			(end -0.67945 -0.305054)
			(stroke
				(width 0.1)
				(type default)
			)
			(layer "F.Fab")
		)
		(pad "1" smd rect
			(at -0.40005 0 270)
			(size 0.4572 0.508)
			(layers "F.Cu" "F.Mask" "F.Paste")
			(net "USB2_HUB_2_EXT_DP")
		)
		(pad "2" smd rect
			(at 0.40005 0 270)
			(size 0.4572 0.508)
			(layers "F.Cu" "F.Mask" "F.Paste")
			(net "USB2_HUB_2_BUF_EXT_R_DP")
		)
	)
	(footprint ""
		(layer "F.Cu")
		(at 457.529946 -41.01211 180)
		(property "Reference" "R4069"
			(at 0 0 180)
			(layer "F.SilkS")
			(hide yes)
			(effects
				(font
					(size 1.27 1.27)
				)
			)
		)
		(property "Value" ""
			(at 0 0 180)
			(layer "F.Fab")
			(effects
				(font
					(size 1.27 1.27)
				)
			)
		)
		(duplicate_pad_numbers_are_jumpers no)
		(fp_line
			(start 0.7874 0.4064)
			(end -0.7874 0.4064)
			(stroke
				(width 0.1524)
				(type default)
			)
			(layer "F.SilkS")
		)
		(fp_line
			(start 0.7874 -0.4064)
			(end 0.7874 0.4064)
			(stroke
				(width 0.1524)
				(type default)
			)
			(layer "F.SilkS")
		)
		(fp_line
			(start -0.7874 0.4064)
			(end -0.7874 -0.4064)
			(stroke
				(width 0.1524)
				(type default)
			)
			(layer "F.SilkS")
		)
		(fp_line
			(start -0.7874 -0.4064)
			(end 0.7874 -0.4064)
			(stroke
				(width 0.1524)
				(type default)
			)
			(layer "F.SilkS")
		)
		(fp_line
			(start 0.67945 0.3048)
			(end 0.120396 0.3048)
			(stroke
				(width 0.1)
				(type default)
			)
			(layer "F.Fab")
		)
		(fp_line
			(start 0.67945 -0.3048)
			(end 0.67945 0.3048)
			(stroke
				(width 0.1)
				(type default)
			)
			(layer "F.Fab")
		)
		(fp_line
			(start 0.12065 -0.2794)
			(end 0.12065 -0.3048)
			(stroke
				(width 0.1)
				(type default)
			)
			(layer "F.Fab")
		)
		(fp_line
			(start 0.12065 -0.3048)
			(end 0.67945 -0.3048)
			(stroke
				(width 0.1)
				(type default)
			)
			(layer "F.Fab")
		)
		(fp_line
			(start 0.120396 0.3048)
			(end 0.120396 0.2794)
			(stroke
				(width 0.1)
				(type default)
			)
			(layer "F.Fab")
		)
		(fp_line
			(start 0.120396 0.2794)
			(end -0.12065 0.2794)
			(stroke
				(width 0.1)
				(type default)
			)
			(layer "F.Fab")
		)
		(fp_line
			(start -0.12065 0.3048)
			(end -0.67945 0.3048)
			(stroke
				(width 0.1)
				(type default)
			)
			(layer "F.Fab")
		)
		(fp_line
			(start -0.12065 0.2794)
			(end -0.12065 0.3048)
			(stroke
				(width 0.1)
				(type default)
			)
			(layer "F.Fab")
		)
		(fp_line
			(start -0.12065 -0.2794)
			(end 0.12065 -0.2794)
			(stroke
				(width 0.1)
				(type default)
			)
			(layer "F.Fab")
		)
		(fp_line
			(start -0.12065 -0.305054)
			(end -0.12065 -0.2794)
			(stroke
				(width 0.1)
				(type default)
			)
			(layer "F.Fab")
		)
		(fp_line
			(start -0.67945 0.3048)
			(end -0.67945 -0.305054)
			(stroke
				(width 0.1)
				(type default)
			)
			(layer "F.Fab")
		)
		(fp_line
			(start -0.67945 -0.305054)
			(end -0.12065 -0.305054)
			(stroke
				(width 0.1)
				(type default)
			)
			(layer "F.Fab")
		)
		(pad "1" smd circle
			(at -0.40005 0 180)
			(size 0 0)
			(layers "F.Cu" "F.Mask" "F.Paste")
			(net "P3V3_OCP_EN_1_R")
		)
		(pad "2" smd circle
			(at 0.40005 0 180)
			(size 0 0)
			(layers "F.Cu" "F.Mask" "F.Paste")
			(net "GND")
		)
	)
	(footprint ""
		(layer "F.Cu")
		(at 311.021476 -28.951428 180)
		(property "Reference" "R1452"
			(at 0 0 180)
			(layer "F.SilkS")
			(hide yes)
			(effects
				(font
					(size 1.27 1.27)
				)
			)
		)
		(property "Value" ""
			(at 0 0 180)
			(layer "F.Fab")
			(effects
				(font
					(size 1.27 1.27)
				)
			)
		)
		(duplicate_pad_numbers_are_jumpers no)
		(fp_line
			(start 0.7874 0.4064)
			(end -0.7874 0.4064)
			(stroke
				(width 0.1524)
				(type default)
			)
			(layer "F.SilkS")
		)
		(fp_line
			(start 0.7874 -0.4064)
			(end 0.7874 0.4064)
			(stroke
				(width 0.1524)
				(type default)
			)
			(layer "F.SilkS")
		)
		(fp_line
			(start -0.7874 0.4064)
			(end -0.7874 -0.4064)
			(stroke
				(width 0.1524)
				(type default)
			)
			(layer "F.SilkS")
		)
		(fp_line
			(start -0.7874 -0.4064)
			(end 0.7874 -0.4064)
			(stroke
				(width 0.1524)
				(type default)
			)
			(layer "F.SilkS")
		)
		(fp_line
			(start 0.67945 0.3048)
			(end 0.120396 0.3048)
			(stroke
				(width 0.1)
				(type default)
			)
			(layer "F.Fab")
		)
		(fp_line
			(start 0.67945 -0.3048)
			(end 0.67945 0.3048)
			(stroke
				(width 0.1)
				(type default)
			)
			(layer "F.Fab")
		)
		(fp_line
			(start 0.12065 -0.2794)
			(end 0.12065 -0.3048)
			(stroke
				(width 0.1)
				(type default)
			)
			(layer "F.Fab")
		)
		(fp_line
			(start 0.12065 -0.3048)
			(end 0.67945 -0.3048)
			(stroke
				(width 0.1)
				(type default)
			)
			(layer "F.Fab")
		)
		(fp_line
			(start 0.120396 0.3048)
			(end 0.120396 0.2794)
			(stroke
				(width 0.1)
				(type default)
			)
			(layer "F.Fab")
		)
		(fp_line
			(start 0.120396 0.2794)
			(end -0.12065 0.2794)
			(stroke
				(width 0.1)
				(type default)
			)
			(layer "F.Fab")
		)
		(fp_line
			(start -0.12065 0.3048)
			(end -0.67945 0.3048)
			(stroke
				(width 0.1)
				(type default)
			)
			(layer "F.Fab")
		)
		(fp_line
			(start -0.12065 0.2794)
			(end -0.12065 0.3048)
			(stroke
				(width 0.1)
				(type default)
			)
			(layer "F.Fab")
		)
		(fp_line
			(start -0.12065 -0.2794)
			(end 0.12065 -0.2794)
			(stroke
				(width 0.1)
				(type default)
			)
			(layer "F.Fab")
		)
		(fp_line
			(start -0.12065 -0.305054)
			(end -0.12065 -0.2794)
			(stroke
				(width 0.1)
				(type default)
			)
			(layer "F.Fab")
		)
		(fp_line
			(start -0.67945 0.3048)
			(end -0.67945 -0.305054)
			(stroke
				(width 0.1)
				(type default)
			)
			(layer "F.Fab")
		)
		(fp_line
			(start -0.67945 -0.305054)
			(end -0.12065 -0.305054)
			(stroke
				(width 0.1)
				(type default)
			)
			(layer "F.Fab")
		)
		(pad "1" smd circle
			(at -0.40005 0 180)
			(size 0 0)
			(layers "F.Cu" "F.Mask" "F.Paste")
			(net "PU_SMB_SML3_3V3AUX_PCH_SDA")
		)
		(pad "2" smd circle
			(at 0.40005 0 180)
			(size 0 0)
			(layers "F.Cu" "F.Mask" "F.Paste")
			(net "P3V3_AUX")
		)
	)
	(footprint ""
		(layer "F.Cu")
		(at 64.979296 -70.78599)
		(property "Reference" "D70"
			(at -34.630106 50.178462 90)
			(unlocked yes)
			(layer "F.SilkS")
			(effects
				(font
					(size 0.635 0.4064)
					(thickness 0.1524)
				)
				(justify left)
			)
		)
		(property "Value" ""
			(at 0 0 0)
			(layer "F.Fab")
			(effects
				(font
					(size 1.27 1.27)
				)
			)
		)
		(duplicate_pad_numbers_are_jumpers no)
		(fp_line
			(start -0.90678 0.4826)
			(end -0.90678 -0.4699)
			(stroke
				(width 0.1524)
				(type default)
			)
			(layer "F.SilkS")
		)
		(fp_line
			(start -0.89408 -0.4826)
			(end 0.90678 -0.4826)
			(stroke
				(width 0.1524)
				(type default)
			)
			(layer "F.SilkS")
		)
		(fp_line
			(start -0.79248 -0.4826)
			(end 1.03378 -0.4826)
			(stroke
				(width 0.1524)
				(type default)
			)
			(layer "F.SilkS")
		)
		(fp_line
			(start -0.64008 -0.4826)
			(end 1.16078 -0.4826)
			(stroke
				(width 0.1524)
				(type default)
			)
			(layer "F.SilkS")
		)
		(fp_line
			(start 0.90678 -0.4826)
			(end 0.90678 0.4826)
			(stroke
				(width 0.1524)
				(type default)
			)
			(layer "F.SilkS")
		)
		(fp_line
			(start 0.90678 0.4826)
			(end -0.90678 0.4826)
			(stroke
				(width 0.1524)
				(type default)
			)
			(layer "F.SilkS")
		)
		(fp_line
			(start 1.03378 -0.4826)
			(end 1.03378 0.4826)
			(stroke
				(width 0.1524)
				(type default)
			)
			(layer "F.SilkS")
		)
		(fp_line
			(start 1.03378 0.4826)
			(end -0.79248 0.4826)
			(stroke
				(width 0.1524)
				(type default)
			)
			(layer "F.SilkS")
		)
		(fp_line
			(start 1.16078 -0.4826)
			(end 1.16078 0.4826)
			(stroke
				(width 0.1524)
				(type default)
			)
			(layer "F.SilkS")
		)
		(fp_line
			(start 1.16078 0.4826)
			(end -0.64008 0.4826)
			(stroke
				(width 0.1524)
				(type default)
			)
			(layer "F.SilkS")
		)
		(fp_line
			(start -0.499872 -0.249936)
			(end 0.499872 -0.249936)
			(stroke
				(width 0.1)
				(type default)
			)
			(layer "F.Fab")
		)
		(fp_line
			(start -0.499872 0.249936)
			(end -0.499872 -0.249936)
			(stroke
				(width 0.1)
				(type default)
			)
			(layer "F.Fab")
		)
		(fp_line
			(start 0.499872 -0.249936)
			(end 0.499872 0.249936)
			(stroke
				(width 0.1)
				(type default)
			)
			(layer "F.Fab")
		)
		(fp_line
			(start 0.499872 0.249936)
			(end -0.499872 0.249936)
			(stroke
				(width 0.1)
				(type default)
			)
			(layer "F.Fab")
		)
		(pad "A" smd rect
			(at -0.47498 0)
			(size 0.6096 0.7112)
			(layers "F.Cu" "F.Mask" "F.Paste")
			(net "LED_RST_PLD_CPU1_DRAM_CD_N")
		)
		(pad "C" smd rect
			(at 0.47498 0)
			(size 0.6096 0.7112)
			(layers "F.Cu" "F.Mask" "F.Paste")
			(net "LED_RST_PLD_CPU1_DRAM_CD_N_D")
		)
	)
	(footprint ""
		(layer "F.Cu")
		(at 216.065608 -400.759422)
		(property "Reference" "PR3921"
			(at 0 0 0)
			(layer "F.SilkS")
			(hide yes)
			(effects
				(font
					(size 1.27 1.27)
				)
			)
		)
		(property "Value" ""
			(at 0 0 0)
			(layer "F.Fab")
			(effects
				(font
					(size 1.27 1.27)
				)
			)
		)
		(duplicate_pad_numbers_are_jumpers no)
		(fp_line
			(start -0.7874 -0.4064)
			(end 0.7874 -0.4064)
			(stroke
				(width 0.1524)
				(type default)
			)
			(layer "F.SilkS")
		)
		(fp_line
			(start -0.7874 0.4064)
			(end -0.7874 -0.4064)
			(stroke
				(width 0.1524)
				(type default)
			)
			(layer "F.SilkS")
		)
		(fp_line
			(start 0.7874 -0.4064)
			(end 0.7874 0.4064)
			(stroke
				(width 0.1524)
				(type default)
			)
			(layer "F.SilkS")
		)
		(fp_line
			(start 0.7874 0.4064)
			(end -0.7874 0.4064)
			(stroke
				(width 0.1524)
				(type default)
			)
			(layer "F.SilkS")
		)
		(fp_line
			(start -0.67945 -0.305054)
			(end -0.12065 -0.305054)
			(stroke
				(width 0.1)
				(type default)
			)
			(layer "F.Fab")
		)
		(fp_line
			(start -0.67945 0.3048)
			(end -0.67945 -0.305054)
			(stroke
				(width 0.1)
				(type default)
			)
			(layer "F.Fab")
		)
		(fp_line
			(start -0.12065 -0.305054)
			(end -0.12065 -0.2794)
			(stroke
				(width 0.1)
				(type default)
			)
			(layer "F.Fab")
		)
		(fp_line
			(start -0.12065 -0.2794)
			(end 0.12065 -0.2794)
			(stroke
				(width 0.1)
				(type default)
			)
			(layer "F.Fab")
		)
		(fp_line
			(start -0.12065 0.2794)
			(end -0.12065 0.3048)
			(stroke
				(width 0.1)
				(type default)
			)
			(layer "F.Fab")
		)
		(fp_line
			(start -0.12065 0.3048)
			(end -0.67945 0.3048)
			(stroke
				(width 0.1)
				(type default)
			)
			(layer "F.Fab")
		)
		(fp_line
			(start 0.120396 0.2794)
			(end -0.12065 0.2794)
			(stroke
				(width 0.1)
				(type default)
			)
			(layer "F.Fab")
		)
		(fp_line
			(start 0.120396 0.3048)
			(end 0.120396 0.2794)
			(stroke
				(width 0.1)
				(type default)
			)
			(layer "F.Fab")
		)
		(fp_line
			(start 0.12065 -0.3048)
			(end 0.67945 -0.3048)
			(stroke
				(width 0.1)
				(type default)
			)
			(layer "F.Fab")
		)
		(fp_line
			(start 0.12065 -0.2794)
			(end 0.12065 -0.3048)
			(stroke
				(width 0.1)
				(type default)
			)
			(layer "F.Fab")
		)
		(fp_line
			(start 0.67945 -0.3048)
			(end 0.67945 0.3048)
			(stroke
				(width 0.1)
				(type default)
			)
			(layer "F.Fab")
		)
		(fp_line
			(start 0.67945 0.3048)
			(end 0.120396 0.3048)
			(stroke
				(width 0.1)
				(type default)
			)
			(layer "F.Fab")
		)
		(pad "1" smd circle
			(at -0.40005 0)
			(size 0 0)
			(layers "F.Cu" "F.Mask" "F.Paste")
			(net "HSC_D_OC_2")
		)
		(pad "2" smd circle
			(at 0.40005 0)
			(size 0 0)
			(layers "F.Cu" "F.Mask" "F.Paste")
			(net "HSC_D_OC_R")
		)
	)
)
